(kicad_pcb
	(version 20241229)
	(generator "pcbnew")
	(generator_version "9.0")
	(general
		(thickness 1.294)
		(legacy_teardrops no)
	)
	(paper "A3")
	(title_block
		(title "Kintex 410T devboard")
		(date "2024-04-03")
		(rev "1.1.2")
		(comment 9 "footprints 521-526 of 975")
	)
	(layers
		(0 "F.Cu" mixed)
		(4 "In1.Cu" power)
		(6 "In2.Cu" power)
		(8 "In3.Cu" mixed)
		(10 "In4.Cu" power)
		(12 "In5.Cu" mixed)
		(14 "In6.Cu" power)
		(16 "In7.Cu" mixed)
		(18 "In8.Cu" power)
		(2 "B.Cu" mixed)
		(9 "F.Adhes" user "F.Adhesive")
		(11 "B.Adhes" user "B.Adhesive")
		(13 "F.Paste" user)
		(15 "B.Paste" user)
		(5 "F.SilkS" user "F.Silkscreen")
		(7 "B.SilkS" user "B.Silkscreen")
		(1 "F.Mask" user)
		(3 "B.Mask" user)
		(17 "Dwgs.User" user "User.Drawings")
		(19 "Cmts.User" user "User.Comments")
		(21 "Eco1.User" user "User.Eco1")
		(23 "Eco2.User" user "User.Eco2")
		(25 "Edge.Cuts" user)
		(27 "Margin" user)
		(31 "F.CrtYd" user "F.Courtyard")
		(29 "B.CrtYd" user "B.Courtyard")
		(35 "F.Fab" user)
		(33 "B.Fab" user)
	)
	(footprint "antmicro-footprints:R_0402_1005Metric"
		(layer "B.Cu")
		(at 204.101 74.233 90)
		(descr "Resistor SMD 0402")
		(tags "resistor SMD 0402")
		(property "Reference" "R2"
			(at -0.767 0.424 270)
			(layer "B.SilkS")
			(effects
				(font
					(size 0.7 0.7)
					(thickness 0.15)
				)
				(justify left bottom mirror)
			)
		)
		(property "Value" "R_10k_0402"
			(at 0 -1.4 270)
			(layer "B.Fab")
			(effects
				(font
					(size 0.7 0.7)
					(thickness 0.15)
				)
				(justify left bottom mirror)
			)
		)
		(property "Description" "SMD Chip Resistor, 10 kohm, ± 1%, 62.5 mW, 0402 [1005 Metric], Thick Film, General Purpose"
			(at 0 0 90)
			(layer "F.Fab")
			(hide yes)
			(effects
				(font
					(size 1.27 1.27)
					(thickness 0.15)
				)
			)
		)
		(property "Author" "Antmicro"
			(at 278.334 -129.868 0)
			(layer "B.Fab")
			(hide yes)
			(effects
				(font
					(size 1 1)
					(thickness 0.15)
				)
				(justify mirror)
			)
		)
		(property "DNP" "DNP"
			(at 278.334 -129.868 0)
			(layer "B.Fab")
			(hide yes)
			(effects
				(font
					(size 1 1)
					(thickness 0.15)
				)
				(justify mirror)
			)
		)
		(property "License" "Apache-2.0"
			(at 278.334 -129.868 0)
			(layer "B.Fab")
			(hide yes)
			(effects
				(font
					(size 1 1)
					(thickness 0.15)
				)
				(justify mirror)
			)
		)
		(property "MPN" "CR0402-FX-1002GLF"
			(at 278.334 -129.868 0)
			(layer "B.Fab")
			(hide yes)
			(effects
				(font
					(size 1 1)
					(thickness 0.15)
				)
				(justify mirror)
			)
		)
		(property "Manufacturer" "Bourns"
			(at 278.334 -129.868 0)
			(layer "B.Fab")
			(hide yes)
			(effects
				(font
					(size 1 1)
					(thickness 0.15)
				)
				(justify mirror)
			)
		)
		(property "Tolerance" "1%"
			(at 278.334 -129.868 0)
			(layer "B.Fab")
			(hide yes)
			(effects
				(font
					(size 1 1)
					(thickness 0.15)
				)
				(justify mirror)
			)
		)
		(property "Val" "10k"
			(at 278.334 -129.868 0)
			(layer "B.Fab")
			(hide yes)
			(effects
				(font
					(size 1 1)
					(thickness 0.15)
				)
				(justify mirror)
			)
		)
		(property "dnp" ""
			(at 278.334 -129.868 0)
			(layer "B.Fab")
			(hide yes)
			(effects
				(font
					(size 1 1)
					(thickness 0.15)
				)
				(justify mirror)
			)
		)
		(property "exclude_from_bom" ""
			(at 278.334 -129.868 0)
			(layer "B.Fab")
			(hide yes)
			(effects
				(font
					(size 1 1)
					(thickness 0.15)
				)
				(justify mirror)
			)
		)
		(sheetname "FPGA Config")
		(sheetfile "fpga-config.kicad_sch")
		(attr smd exclude_from_bom)
		(fp_rect
			(start -0.925 0.47)
			(end 0.925 -0.47)
			(stroke
				(width 0.05)
				(type default)
			)
			(fill no)
			(layer "B.CrtYd")
		)
		(fp_rect
			(start -0.5 0.25)
			(end 0.5 -0.25)
			(stroke
				(width 0.15)
				(type solid)
			)
			(fill no)
			(layer "B.Fab")
		)
		(pad "1" smd roundrect
			(at -0.48 0 90)
			(size 0.59 0.64)
			(layers "B.Cu" "B.Mask" "B.Paste")
			(roundrect_rratio 0.25)
			(net 298 "/FPGA Config/MODE2")
			(pintype "passive")
		)
		(pad "2" smd roundrect
			(at 0.48 0 90)
			(size 0.59 0.64)
			(layers "B.Cu" "B.Mask" "B.Paste")
			(roundrect_rratio 0.25)
			(net 24 "+3V3")
			(pintype "passive")
		)
	)
	(footprint "antmicro-footprints:C_0402_1005Metric"
		(layer "B.Cu")
		(at 192.5 135)
		(descr "Capacitor SMD 0402")
		(tags "capacitor SMD 0402")
		(property "Reference" "C101"
			(at 22.925 -28.075 180)
			(layer "B.SilkS")
			(effects
				(font
					(size 0.7 0.7)
					(thickness 0.15)
				)
				(justify left bottom mirror)
			)
		)
		(property "Value" "C_100n_0402"
			(at 0 -1.169 180)
			(layer "B.Fab")
			(effects
				(font
					(size 0.7 0.7)
					(thickness 0.15)
				)
				(justify left bottom mirror)
			)
		)
		(property "Description" "SMD Multilayer Ceramic Capacitor, 0.1 µF, 50 V, 0402 [1005 Metric], ± 10%, X5R, GRM Series"
			(at 0 0 0)
			(layer "F.Fab")
			(hide yes)
			(effects
				(font
					(size 1.27 1.27)
					(thickness 0.15)
				)
			)
		)
		(property "Author" "Antmicro"
			(at 0 0 0)
			(layer "B.Fab")
			(hide yes)
			(effects
				(font
					(size 1 1)
					(thickness 0.15)
				)
				(justify mirror)
			)
		)
		(property "Dielectric" "X5R"
			(at 0 0 0)
			(layer "B.Fab")
			(hide yes)
			(effects
				(font
					(size 1 1)
					(thickness 0.15)
				)
				(justify mirror)
			)
		)
		(property "License" "Apache-2.0"
			(at 0 0 0)
			(layer "B.Fab")
			(hide yes)
			(effects
				(font
					(size 1 1)
					(thickness 0.15)
				)
				(justify mirror)
			)
		)
		(property "MPN" "GRM155R61H104KE14D"
			(at 0 0 0)
			(layer "B.Fab")
			(hide yes)
			(effects
				(font
					(size 1 1)
					(thickness 0.15)
				)
				(justify mirror)
			)
		)
		(property "Manufacturer" "Murata"
			(at 0 0 0)
			(layer "B.Fab")
			(hide yes)
			(effects
				(font
					(size 1 1)
					(thickness 0.15)
				)
				(justify mirror)
			)
		)
		(property "Val" "100n"
			(at 0 0 0)
			(layer "B.Fab")
			(hide yes)
			(effects
				(font
					(size 1 1)
					(thickness 0.15)
				)
				(justify mirror)
			)
		)
		(property "Voltage" "50V"
			(at 0 0 0)
			(layer "B.Fab")
			(hide yes)
			(effects
				(font
					(size 1 1)
					(thickness 0.15)
				)
				(justify mirror)
			)
		)
		(sheetname "FPGA Bank 33 & 34")
		(sheetfile "fpga-bank-33-34.kicad_sch")
		(attr smd)
		(fp_rect
			(start -0.925 0.47)
			(end 0.925 -0.47)
			(stroke
				(width 0.05)
				(type default)
			)
			(fill no)
			(layer "B.CrtYd")
		)
		(fp_line
			(start -0.494 -0.248)
			(end -0.494 0.25)
			(stroke
				(width 0.15)
				(type solid)
			)
			(layer "B.Fab")
		)
		(fp_line
			(start -0.494 0.25)
			(end 0.504 0.25)
			(stroke
				(width 0.15)
				(type solid)
			)
			(layer "B.Fab")
		)
		(fp_line
			(start 0.504 -0.248)
			(end -0.494 -0.248)
			(stroke
				(width 0.15)
				(type solid)
			)
			(layer "B.Fab")
		)
		(fp_line
			(start 0.504 0.25)
			(end 0.504 -0.248)
			(stroke
				(width 0.15)
				(type solid)
			)
			(layer "B.Fab")
		)
		(pad "1" smd roundrect
			(at -0.48 0)
			(size 0.59 0.64)
			(layers "B.Cu" "B.Mask" "B.Paste")
			(roundrect_rratio 0.25)
			(net 1 "GND")
			(pintype "passive")
		)
		(pad "2" smd roundrect
			(at 0.48 0)
			(size 0.59 0.64)
			(layers "B.Cu" "B.Mask" "B.Paste")
			(roundrect_rratio 0.25)
			(net 26 "+1V8")
			(pintype "passive")
		)
	)
	(footprint "antmicro-footprints:C_0402_1005Metric"
		(layer "B.Cu")
		(at 259.851 124.55 180)
		(descr "Capacitor SMD 0402")
		(tags "capacitor SMD 0402")
		(property "Reference" "C401"
			(at -1.349 -1.225 0)
			(layer "B.SilkS")
			(effects
				(font
					(size 0.7 0.7)
					(thickness 0.15)
				)
				(justify left bottom mirror)
			)
		)
		(property "Value" "C_100n_0402"
			(at 0 -1.169 0)
			(layer "B.Fab")
			(effects
				(font
					(size 0.7 0.7)
					(thickness 0.15)
				)
				(justify left bottom mirror)
			)
		)
		(property "Description" "SMD Multilayer Ceramic Capacitor, 0.1 µF, 50 V, 0402 [1005 Metric], ± 10%, X5R, GRM Series"
			(at 0 0 180)
			(layer "F.Fab")
			(hide yes)
			(effects
				(font
					(size 1.27 1.27)
					(thickness 0.15)
				)
			)
		)
		(property "Author" "Antmicro"
			(at 519.702 249.1 0)
			(layer "B.Fab")
			(hide yes)
			(effects
				(font
					(size 1 1)
					(thickness 0.15)
				)
				(justify mirror)
			)
		)
		(property "Dielectric" "X5R"
			(at 519.702 249.1 0)
			(layer "B.Fab")
			(hide yes)
			(effects
				(font
					(size 1 1)
					(thickness 0.15)
				)
				(justify mirror)
			)
		)
		(property "License" "Apache-2.0"
			(at 519.702 249.1 0)
			(layer "B.Fab")
			(hide yes)
			(effects
				(font
					(size 1 1)
					(thickness 0.15)
				)
				(justify mirror)
			)
		)
		(property "MPN" "GRM155R61H104KE14D"
			(at 519.702 249.1 0)
			(layer "B.Fab")
			(hide yes)
			(effects
				(font
					(size 1 1)
					(thickness 0.15)
				)
				(justify mirror)
			)
		)
		(property "Manufacturer" "Murata"
			(at 519.702 249.1 0)
			(layer "B.Fab")
			(hide yes)
			(effects
				(font
					(size 1 1)
					(thickness 0.15)
				)
				(justify mirror)
			)
		)
		(property "Val" "100n"
			(at 519.702 249.1 0)
			(layer "B.Fab")
			(hide yes)
			(effects
				(font
					(size 1 1)
					(thickness 0.15)
				)
				(justify mirror)
			)
		)
		(property "Voltage" "50V"
			(at 519.702 249.1 0)
			(layer "B.Fab")
			(hide yes)
			(effects
				(font
					(size 1 1)
					(thickness 0.15)
				)
				(justify mirror)
			)
		)
		(sheetname "USB PHY")
		(sheetfile "usb-phy.kicad_sch")
		(attr smd)
		(fp_rect
			(start -0.925 0.47)
			(end 0.925 -0.47)
			(stroke
				(width 0.05)
				(type default)
			)
			(fill no)
			(layer "B.CrtYd")
		)
		(fp_line
			(start 0.504 0.25)
			(end 0.504 -0.248)
			(stroke
				(width 0.15)
				(type solid)
			)
			(layer "B.Fab")
		)
		(fp_line
			(start 0.504 -0.248)
			(end -0.494 -0.248)
			(stroke
				(width 0.15)
				(type solid)
			)
			(layer "B.Fab")
		)
		(fp_line
			(start -0.494 0.25)
			(end 0.504 0.25)
			(stroke
				(width 0.15)
				(type solid)
			)
			(layer "B.Fab")
		)
		(fp_line
			(start -0.494 -0.248)
			(end -0.494 0.25)
			(stroke
				(width 0.15)
				(type solid)
			)
			(layer "B.Fab")
		)
		(pad "1" smd roundrect
			(at -0.48 0 180)
			(size 0.59 0.64)
			(layers "B.Cu" "B.Mask" "B.Paste")
			(roundrect_rratio 0.25)
			(net 1 "GND")
			(pintype "passive")
		)
		(pad "2" smd roundrect
			(at 0.48 0 180)
			(size 0.59 0.64)
			(layers "B.Cu" "B.Mask" "B.Paste")
			(roundrect_rratio 0.25)
			(net 707 "/USB PHY/FTDI_3V3")
			(pintype "passive")
		)
	)
	(footprint "antmicro-footprints:R_0402_1005Metric"
		(layer "B.Cu")
		(at 261.5 93.4)
		(descr "Resistor SMD 0402")
		(tags "resistor SMD 0402")
		(property "Reference" "R128"
			(at 1.325 1.25 180)
			(layer "B.SilkS")
			(effects
				(font
					(size 0.7 0.7)
					(thickness 0.15)
				)
				(justify left bottom mirror)
			)
		)
		(property "Value" "R_1k_0402"
			(at 0 -1.4 180)
			(layer "B.Fab")
			(effects
				(font
					(size 0.7 0.7)
					(thickness 0.15)
				)
				(justify left bottom mirror)
			)
		)
		(property "Description" "SMD Chip Resistor, 1 kohm, ± 1%, 63 mW, 0402 [1005 Metric], Thick Film, General Purpose"
			(at 0 0 0)
			(layer "F.Fab")
			(hide yes)
			(effects
				(font
					(size 1.27 1.27)
					(thickness 0.15)
				)
			)
		)
		(property "Author" "Antmicro"
			(at 0 0 0)
			(layer "B.Fab")
			(hide yes)
			(effects
				(font
					(size 1 1)
					(thickness 0.15)
				)
				(justify mirror)
			)
		)
		(property "License" "Apache-2.0"
			(at 0 0 0)
			(layer "B.Fab")
			(hide yes)
			(effects
				(font
					(size 1 1)
					(thickness 0.15)
				)
				(justify mirror)
			)
		)
		(property "MPN" "CR0402-FX-1001GLF"
			(at 0 0 0)
			(layer "B.Fab")
			(hide yes)
			(effects
				(font
					(size 1 1)
					(thickness 0.15)
				)
				(justify mirror)
			)
		)
		(property "Manufacturer" "Bourns"
			(at 0 0 0)
			(layer "B.Fab")
			(hide yes)
			(effects
				(font
					(size 1 1)
					(thickness 0.15)
				)
				(justify mirror)
			)
		)
		(property "Tolerance" "1%"
			(at 0 0 0)
			(layer "B.Fab")
			(hide yes)
			(effects
				(font
					(size 1 1)
					(thickness 0.15)
				)
				(justify mirror)
			)
		)
		(property "Val" "1k"
			(at 0 0 0)
			(layer "B.Fab")
			(hide yes)
			(effects
				(font
					(size 1 1)
					(thickness 0.15)
				)
				(justify mirror)
			)
		)
		(sheetname "User GPIO + LED + button + DIP switch")
		(sheetfile "user-gpio.kicad_sch")
		(attr smd)
		(fp_rect
			(start -0.925 0.47)
			(end 0.925 -0.47)
			(stroke
				(width 0.05)
				(type default)
			)
			(fill no)
			(layer "B.CrtYd")
		)
		(fp_rect
			(start -0.5 0.25)
			(end 0.5 -0.25)
			(stroke
				(width 0.15)
				(type solid)
			)
			(fill no)
			(layer "B.Fab")
		)
		(pad "1" smd roundrect
			(at -0.48 0)
			(size 0.59 0.64)
			(layers "B.Cu" "B.Mask" "B.Paste")
			(roundrect_rratio 0.25)
			(net 24 "+3V3")
			(pintype "passive")
		)
		(pad "2" smd roundrect
			(at 0.48 0)
			(size 0.59 0.64)
			(layers "B.Cu" "B.Mask" "B.Paste")
			(roundrect_rratio 0.25)
			(net 783 "Net-(D22-A)")
			(pintype "passive")
		)
	)
	(footprint "antmicro-footprints:C_0402_1005Metric"
		(layer "B.Cu")
		(at 201.5 141 90)
		(descr "Capacitor SMD 0402")
		(tags "capacitor SMD 0402")
		(property "Reference" "C83"
			(at 1.15 1.275 270)
			(layer "B.SilkS")
			(effects
				(font
					(size 0.7 0.7)
					(thickness 0.15)
				)
				(justify left bottom mirror)
			)
		)
		(property "Value" "C_100n_0402"
			(at 0 -1.169 270)
			(layer "B.Fab")
			(effects
				(font
					(size 0.7 0.7)
					(thickness 0.15)
				)
				(justify left bottom mirror)
			)
		)
		(property "Description" "SMD Multilayer Ceramic Capacitor, 0.1 µF, 50 V, 0402 [1005 Metric], ± 10%, X5R, GRM Series"
			(at 0 0 90)
			(layer "F.Fab")
			(hide yes)
			(effects
				(font
					(size 1.27 1.27)
					(thickness 0.15)
				)
			)
		)
		(property "Author" "Antmicro"
			(at 342.5 -60.5 0)
			(layer "B.Fab")
			(hide yes)
			(effects
				(font
					(size 1 1)
					(thickness 0.15)
				)
				(justify mirror)
			)
		)
		(property "Dielectric" "X5R"
			(at 342.5 -60.5 0)
			(layer "B.Fab")
			(hide yes)
			(effects
				(font
					(size 1 1)
					(thickness 0.15)
				)
				(justify mirror)
			)
		)
		(property "License" "Apache-2.0"
			(at 342.5 -60.5 0)
			(layer "B.Fab")
			(hide yes)
			(effects
				(font
					(size 1 1)
					(thickness 0.15)
				)
				(justify mirror)
			)
		)
		(property "MPN" "GRM155R61H104KE14D"
			(at 342.5 -60.5 0)
			(layer "B.Fab")
			(hide yes)
			(effects
				(font
					(size 1 1)
					(thickness 0.15)
				)
				(justify mirror)
			)
		)
		(property "Manufacturer" "Murata"
			(at 342.5 -60.5 0)
			(layer "B.Fab")
			(hide yes)
			(effects
				(font
					(size 1 1)
					(thickness 0.15)
				)
				(justify mirror)
			)
		)
		(property "Val" "100n"
			(at 342.5 -60.5 0)
			(layer "B.Fab")
			(hide yes)
			(effects
				(font
					(size 1 1)
					(thickness 0.15)
				)
				(justify mirror)
			)
		)
		(property "Voltage" "50V"
			(at 342.5 -60.5 0)
			(layer "B.Fab")
			(hide yes)
			(effects
				(font
					(size 1 1)
					(thickness 0.15)
				)
				(justify mirror)
			)
		)
		(sheetname "FPGA Bank 18 & 32")
		(sheetfile "fpga-bank-18-32.kicad_sch")
		(attr smd)
		(fp_rect
			(start -0.925 0.47)
			(end 0.925 -0.47)
			(stroke
				(width 0.05)
				(type default)
			)
			(fill no)
			(layer "B.CrtYd")
		)
		(fp_line
			(start 0.504 -0.248)
			(end -0.494 -0.248)
			(stroke
				(width 0.15)
				(type solid)
			)
			(layer "B.Fab")
		)
		(fp_line
			(start -0.494 -0.248)
			(end -0.494 0.25)
			(stroke
				(width 0.15)
				(type solid)
			)
			(layer "B.Fab")
		)
		(fp_line
			(start 0.504 0.25)
			(end 0.504 -0.248)
			(stroke
				(width 0.15)
				(type solid)
			)
			(layer "B.Fab")
		)
		(fp_line
			(start -0.494 0.25)
			(end 0.504 0.25)
			(stroke
				(width 0.15)
				(type solid)
			)
			(layer "B.Fab")
		)
		(pad "1" smd roundrect
			(at -0.48 0 90)
			(size 0.59 0.64)
			(layers "B.Cu" "B.Mask" "B.Paste")
			(roundrect_rratio 0.25)
			(net 1 "GND")
			(pintype "passive")
		)
		(pad "2" smd roundrect
			(at 0.48 0 90)
			(size 0.59 0.64)
			(layers "B.Cu" "B.Mask" "B.Paste")
			(roundrect_rratio 0.25)
			(net 26 "+1V8")
			(pintype "passive")
		)
	)
	(footprint "antmicro-footprints:R_0402_1005Metric"
		(layer "B.Cu")
		(at 190.6 79.8 90)
		(descr "Resistor SMD 0402")
		(tags "resistor SMD 0402")
		(property "Reference" "R145"
			(at -0.725 0.4 270)
			(layer "B.SilkS")
			(effects
				(font
					(size 0.7 0.7)
					(thickness 0.15)
				)
				(justify left bottom mirror)
			)
		)
		(property "Value" "R_100R_0402"
			(at 0 -1.4 270)
			(layer "B.Fab")
			(effects
				(font
					(size 0.7 0.7)
					(thickness 0.15)
				)
				(justify left bottom mirror)
			)
		)
		(property "Description" "SMD Chip Resistor, 100 ohm, ± 1%, 62.5 mW, 0402 [1005 Metric], Thick Film, General Purpose"
			(at 0 0 90)
			(layer "F.Fab")
			(hide yes)
			(effects
				(font
					(size 1.27 1.27)
					(thickness 0.15)
				)
			)
		)
		(property "Author" "Antmicro"
			(at 270.4 -110.8 0)
			(layer "B.Fab")
			(hide yes)
			(effects
				(font
					(size 1 1)
					(thickness 0.15)
				)
				(justify mirror)
			)
		)
		(property "License" "Apache-2.0"
			(at 270.4 -110.8 0)
			(layer "B.Fab")
			(hide yes)
			(effects
				(font
					(size 1 1)
					(thickness 0.15)
				)
				(justify mirror)
			)
		)
		(property "MPN" "CR0402-FX-1000GLF"
			(at 270.4 -110.8 0)
			(layer "B.Fab")
			(hide yes)
			(effects
				(font
					(size 1 1)
					(thickness 0.15)
				)
				(justify mirror)
			)
		)
		(property "Manufacturer" "Bourns"
			(at 270.4 -110.8 0)
			(layer "B.Fab")
			(hide yes)
			(effects
				(font
					(size 1 1)
					(thickness 0.15)
				)
				(justify mirror)
			)
		)
		(property "Tolerance" "1%"
			(at 270.4 -110.8 0)
			(layer "B.Fab")
			(hide yes)
			(effects
				(font
					(size 1 1)
					(thickness 0.15)
				)
				(justify mirror)
			)
		)
		(property "Val" "100R"
			(at 270.4 -110.8 0)
			(layer "B.Fab")
			(hide yes)
			(effects
				(font
					(size 1 1)
					(thickness 0.15)
				)
				(justify mirror)
			)
		)
		(sheetname "User GPIO + LED + button + DIP switch")
		(sheetfile "user-gpio.kicad_sch")
		(attr smd)
		(fp_rect
			(start -0.925 0.47)
			(end 0.925 -0.47)
			(stroke
				(width 0.05)
				(type default)
			)
			(fill no)
			(layer "B.CrtYd")
		)
		(fp_rect
			(start -0.5 0.25)
			(end 0.5 -0.25)
			(stroke
				(width 0.15)
				(type solid)
			)
			(fill no)
			(layer "B.Fab")
		)
		(pad "1" smd roundrect
			(at -0.48 0 90)
			(size 0.59 0.64)
			(layers "B.Cu" "B.Mask" "B.Paste")
			(roundrect_rratio 0.25)
			(net 491 "/FPGA Bank 12 & 13/CW_HEADER.IO2")
			(pintype "passive")
		)
		(pad "2" smd roundrect
			(at 0.48 0 90)
			(size 0.59 0.64)
			(layers "B.Cu" "B.Mask" "B.Paste")
			(roundrect_rratio 0.25)
			(net 829 "/User GPIO + LED + button + DIP switch/CW_20PIN_IO2")
			(pintype "passive")
		)
	)
)
